(kicad_pcb
	(version 20260206)
	(generator "pcbnew")
	(generator_version "10.0")
	(general
		(thickness 1.6)
		(legacy_teardrops no)
	)
	(paper "A4")
	(title_block
		(title "04192023_DAF0TMB3IC0_F0TG_MB_C_brd_V02_OCP.brd")
		(comment 1 "Grand Teton / footprints 1496-1504 of 8354")
	)
	(layers
		(0 "F.Cu" signal "TOP")
		(4 "In1.Cu" signal "GND")
		(6 "In2.Cu" signal "IN1")
		(8 "In3.Cu" signal "GND1")
		(10 "In4.Cu" signal "IN2")
		(12 "In5.Cu" signal "GND2")
		(14 "In6.Cu" signal "IN3")
		(16 "In7.Cu" signal "GND3")
		(18 "In8.Cu" signal "VCC")
		(20 "In9.Cu" signal "VCC1")
		(22 "In10.Cu" signal "GND4")
		(24 "In11.Cu" signal "IN4")
		(26 "In12.Cu" signal "GND5")
		(28 "In13.Cu" signal "IN5")
		(30 "In14.Cu" signal "GND6")
		(32 "In15.Cu" signal "IN6")
		(34 "In16.Cu" signal "GND7")
		(2 "B.Cu" signal "BOTTOM")
		(9 "F.Adhes" user "F.Adhesive")
		(11 "B.Adhes" user "B.Adhesive")
		(13 "F.Paste" user "Package Geometry/Pastemask Top")
		(15 "B.Paste" user "Package Geometry/Pastemask Bottom")
		(5 "F.SilkS" user "Ref Des/Silkscreen Top")
		(7 "B.SilkS" user "Ref Des/Silkscreen Bottom")
		(1 "F.Mask" user "Board Geometry/Soldermask Top")
		(3 "B.Mask" user "Board Geometry/Soldermask Bottom")
		(17 "Dwgs.User" user "User.Drawings")
		(19 "Cmts.User" user "User.Comments")
		(21 "Eco1.User" user "User.Eco1")
		(23 "Eco2.User" user "User.Eco2")
		(25 "Edge.Cuts" user "Board Geometry/Outline")
		(27 "Margin" user)
		(31 "F.CrtYd" user "Package Geometry/Place Bound Top")
		(29 "B.CrtYd" user "Package Geometry/Place Bound Bottom")
		(35 "F.Fab" user "Ref Des/Assembly Top")
		(33 "B.Fab" user "Ref Des/Assembly Bottom")
	)
	(footprint ""
		(layer "F.Cu")
		(at 327.179178 -46.748954)
		(property "Reference" "R1800"
			(at 0 0 0)
			(layer "F.SilkS")
			(hide yes)
			(effects
				(font
					(size 1.27 1.27)
				)
			)
		)
		(property "Value" ""
			(at 0 0 0)
			(layer "F.Fab")
			(effects
				(font
					(size 1.27 1.27)
				)
			)
		)
		(duplicate_pad_numbers_are_jumpers no)
		(fp_line
			(start -0.7874 -0.4064)
			(end 0.7874 -0.4064)
			(stroke
				(width 0.1524)
				(type default)
			)
			(layer "F.SilkS")
		)
		(fp_line
			(start -0.7874 0.4064)
			(end -0.7874 -0.4064)
			(stroke
				(width 0.1524)
				(type default)
			)
			(layer "F.SilkS")
		)
		(fp_line
			(start 0.7874 -0.4064)
			(end 0.7874 0.4064)
			(stroke
				(width 0.1524)
				(type default)
			)
			(layer "F.SilkS")
		)
		(fp_line
			(start 0.7874 0.4064)
			(end -0.7874 0.4064)
			(stroke
				(width 0.1524)
				(type default)
			)
			(layer "F.SilkS")
		)
		(fp_line
			(start -0.67945 -0.305054)
			(end -0.12065 -0.305054)
			(stroke
				(width 0.1)
				(type default)
			)
			(layer "F.Fab")
		)
		(fp_line
			(start -0.67945 0.3048)
			(end -0.67945 -0.305054)
			(stroke
				(width 0.1)
				(type default)
			)
			(layer "F.Fab")
		)
		(fp_line
			(start -0.12065 -0.305054)
			(end -0.12065 -0.2794)
			(stroke
				(width 0.1)
				(type default)
			)
			(layer "F.Fab")
		)
		(fp_line
			(start -0.12065 -0.2794)
			(end 0.12065 -0.2794)
			(stroke
				(width 0.1)
				(type default)
			)
			(layer "F.Fab")
		)
		(fp_line
			(start -0.12065 0.2794)
			(end -0.12065 0.3048)
			(stroke
				(width 0.1)
				(type default)
			)
			(layer "F.Fab")
		)
		(fp_line
			(start -0.12065 0.3048)
			(end -0.67945 0.3048)
			(stroke
				(width 0.1)
				(type default)
			)
			(layer "F.Fab")
		)
		(fp_line
			(start 0.120396 0.2794)
			(end -0.12065 0.2794)
			(stroke
				(width 0.1)
				(type default)
			)
			(layer "F.Fab")
		)
		(fp_line
			(start 0.120396 0.3048)
			(end 0.120396 0.2794)
			(stroke
				(width 0.1)
				(type default)
			)
			(layer "F.Fab")
		)
		(fp_line
			(start 0.12065 -0.3048)
			(end 0.67945 -0.3048)
			(stroke
				(width 0.1)
				(type default)
			)
			(layer "F.Fab")
		)
		(fp_line
			(start 0.12065 -0.2794)
			(end 0.12065 -0.3048)
			(stroke
				(width 0.1)
				(type default)
			)
			(layer "F.Fab")
		)
		(fp_line
			(start 0.67945 -0.3048)
			(end 0.67945 0.3048)
			(stroke
				(width 0.1)
				(type default)
			)
			(layer "F.Fab")
		)
		(fp_line
			(start 0.67945 0.3048)
			(end 0.120396 0.3048)
			(stroke
				(width 0.1)
				(type default)
			)
			(layer "F.Fab")
		)
		(pad "1" smd circle
			(at -0.40005 0)
			(size 0 0)
			(layers "F.Cu" "F.Mask" "F.Paste")
			(net "P12V_AUX_ADC")
		)
		(pad "2" smd circle
			(at 0.40005 0)
			(size 0 0)
			(layers "F.Cu" "F.Mask" "F.Paste")
			(net "GND")
		)
	)
	(footprint ""
		(layer "F.Cu")
		(at 76.07173 -386.684774 -90)
		(property "Reference" "R625"
			(at 0 0 270)
			(layer "F.SilkS")
			(hide yes)
			(effects
				(font
					(size 1.27 1.27)
				)
			)
		)
		(property "Value" ""
			(at 0 0 270)
			(layer "F.Fab")
			(effects
				(font
					(size 1.27 1.27)
				)
			)
		)
		(duplicate_pad_numbers_are_jumpers no)
		(fp_line
			(start -0.32512 0.175006)
			(end -0.32512 -0.175006)
			(stroke
				(width 0.1)
				(type default)
			)
			(layer "F.Fab")
		)
		(fp_line
			(start 0.32512 0.175006)
			(end -0.32512 0.175006)
			(stroke
				(width 0.1)
				(type default)
			)
			(layer "F.Fab")
		)
		(fp_line
			(start -0.32512 -0.175006)
			(end 0.32512 -0.175006)
			(stroke
				(width 0.1)
				(type default)
			)
			(layer "F.Fab")
		)
		(fp_line
			(start 0.32512 -0.175006)
			(end 0.32512 0.175006)
			(stroke
				(width 0.1)
				(type default)
			)
			(layer "F.Fab")
		)
		(pad "1" smd rect
			(at -0.2667 0 270)
			(size 0.3048 0.381)
			(layers "F.Cu" "F.Mask" "F.Paste")
			(net "CLK_100M_RETIMER_CPU1_P1_DN")
		)
		(pad "2" smd rect
			(at 0.2667 0 90)
			(size 0.3048 0.381)
			(layers "F.Cu" "F.Mask" "F.Paste")
			(net "GND")
		)
	)
	(footprint ""
		(layer "F.Cu")
		(at 12.319508 -128.593088 90)
		(property "Reference" "R3340"
			(at 0 0 90)
			(layer "F.SilkS")
			(hide yes)
			(effects
				(font
					(size 1.27 1.27)
				)
			)
		)
		(property "Value" ""
			(at 0 0 90)
			(layer "F.Fab")
			(effects
				(font
					(size 1.27 1.27)
				)
			)
		)
		(duplicate_pad_numbers_are_jumpers no)
		(fp_line
			(start 0.7874 -0.4064)
			(end 0.7874 0.4064)
			(stroke
				(width 0.1524)
				(type default)
			)
			(layer "F.SilkS")
		)
		(fp_line
			(start -0.7874 -0.4064)
			(end 0.7874 -0.4064)
			(stroke
				(width 0.1524)
				(type default)
			)
			(layer "F.SilkS")
		)
		(fp_line
			(start 0.7874 0.4064)
			(end -0.7874 0.4064)
			(stroke
				(width 0.1524)
				(type default)
			)
			(layer "F.SilkS")
		)
		(fp_line
			(start -0.7874 0.4064)
			(end -0.7874 -0.4064)
			(stroke
				(width 0.1524)
				(type default)
			)
			(layer "F.SilkS")
		)
		(fp_line
			(start -0.12065 -0.305054)
			(end -0.12065 -0.2794)
			(stroke
				(width 0.1)
				(type default)
			)
			(layer "F.Fab")
		)
		(fp_line
			(start -0.67945 -0.305054)
			(end -0.12065 -0.305054)
			(stroke
				(width 0.1)
				(type default)
			)
			(layer "F.Fab")
		)
		(fp_line
			(start 0.67945 -0.3048)
			(end 0.67945 0.3048)
			(stroke
				(width 0.1)
				(type default)
			)
			(layer "F.Fab")
		)
		(fp_line
			(start 0.12065 -0.3048)
			(end 0.67945 -0.3048)
			(stroke
				(width 0.1)
				(type default)
			)
			(layer "F.Fab")
		)
		(fp_line
			(start 0.12065 -0.2794)
			(end 0.12065 -0.3048)
			(stroke
				(width 0.1)
				(type default)
			)
			(layer "F.Fab")
		)
		(fp_line
			(start -0.12065 -0.2794)
			(end 0.12065 -0.2794)
			(stroke
				(width 0.1)
				(type default)
			)
			(layer "F.Fab")
		)
		(fp_line
			(start 0.120396 0.2794)
			(end -0.12065 0.2794)
			(stroke
				(width 0.1)
				(type default)
			)
			(layer "F.Fab")
		)
		(fp_line
			(start -0.12065 0.2794)
			(end -0.12065 0.3048)
			(stroke
				(width 0.1)
				(type default)
			)
			(layer "F.Fab")
		)
		(fp_line
			(start 0.67945 0.3048)
			(end 0.120396 0.3048)
			(stroke
				(width 0.1)
				(type default)
			)
			(layer "F.Fab")
		)
		(fp_line
			(start 0.120396 0.3048)
			(end 0.120396 0.2794)
			(stroke
				(width 0.1)
				(type default)
			)
			(layer "F.Fab")
		)
		(fp_line
			(start -0.12065 0.3048)
			(end -0.67945 0.3048)
			(stroke
				(width 0.1)
				(type default)
			)
			(layer "F.Fab")
		)
		(fp_line
			(start -0.67945 0.3048)
			(end -0.67945 -0.305054)
			(stroke
				(width 0.1)
				(type default)
			)
			(layer "F.Fab")
		)
		(pad "1" smd circle
			(at -0.40005 0 90)
			(size 0 0)
			(layers "F.Cu" "F.Mask" "F.Paste")
			(net "SMB_HOST_CLK_3V3AUX_SCL")
		)
		(pad "2" smd circle
			(at 0.40005 0 90)
			(size 0 0)
			(layers "F.Cu" "F.Mask" "F.Paste")
			(net "SMB_HOST_CLK_GEN2_3V3AUX_SCL")
		)
	)
	(footprint ""
		(layer "F.Cu")
		(at 139.890754 -79.273654 90)
		(property "Reference" "PC6014"
			(at 0 0 90)
			(layer "F.SilkS")
			(hide yes)
			(effects
				(font
					(size 1.27 1.27)
				)
			)
		)
		(property "Value" ""
			(at 0 0 90)
			(layer "F.Fab")
			(effects
				(font
					(size 1.27 1.27)
				)
			)
		)
		(duplicate_pad_numbers_are_jumpers no)
		(fp_line
			(start 1.524 -0.762)
			(end 1.524 0.762)
			(stroke
				(width 0.1524)
				(type default)
			)
			(layer "F.SilkS")
		)
		(fp_line
			(start -1.524 -0.762)
			(end 1.524 -0.762)
			(stroke
				(width 0.1524)
				(type default)
			)
			(layer "F.SilkS")
		)
		(fp_line
			(start 1.524 0.762)
			(end -1.524 0.762)
			(stroke
				(width 0.1524)
				(type default)
			)
			(layer "F.SilkS")
		)
		(fp_line
			(start -1.524 0.762)
			(end -1.524 -0.762)
			(stroke
				(width 0.1524)
				(type default)
			)
			(layer "F.SilkS")
		)
		(fp_line
			(start 1.1049 -0.724916)
			(end -1.1049 -0.724916)
			(stroke
				(width 0.1)
				(type default)
			)
			(layer "F.Fab")
		)
		(fp_line
			(start -1.1049 -0.724916)
			(end -1.1049 0.724916)
			(stroke
				(width 0.1)
				(type default)
			)
			(layer "F.Fab")
		)
		(fp_line
			(start 1.1049 0.724916)
			(end 1.1049 -0.724916)
			(stroke
				(width 0.1)
				(type default)
			)
			(layer "F.Fab")
		)
		(fp_line
			(start -1.1049 0.724916)
			(end 1.1049 0.724916)
			(stroke
				(width 0.1)
				(type default)
			)
			(layer "F.Fab")
		)
		(pad "1" smd rect
			(at -0.889 0 270)
			(size 1.016 1.27)
			(layers "F.Cu" "F.Mask" "F.Paste")
			(net "SW_P12V_AUX_P1V8_AUX_FLT")
		)
		(pad "2" smd rect
			(at 0.889 0 270)
			(size 1.016 1.27)
			(layers "F.Cu" "F.Mask" "F.Paste")
			(net "GND")
		)
	)
	(footprint ""
		(layer "F.Cu")
		(at 177.927 -129.377948 90)
		(property "Reference" "R191"
			(at 0 0 90)
			(layer "F.SilkS")
			(hide yes)
			(effects
				(font
					(size 1.27 1.27)
				)
			)
		)
		(property "Value" ""
			(at 0 0 90)
			(layer "F.Fab")
			(effects
				(font
					(size 1.27 1.27)
				)
			)
		)
		(duplicate_pad_numbers_are_jumpers no)
		(fp_line
			(start 0.7874 -0.4064)
			(end 0.7874 0.4064)
			(stroke
				(width 0.1524)
				(type default)
			)
			(layer "F.SilkS")
		)
		(fp_line
			(start -0.7874 -0.4064)
			(end 0.7874 -0.4064)
			(stroke
				(width 0.1524)
				(type default)
			)
			(layer "F.SilkS")
		)
		(fp_line
			(start 0.7874 0.4064)
			(end -0.7874 0.4064)
			(stroke
				(width 0.1524)
				(type default)
			)
			(layer "F.SilkS")
		)
		(fp_line
			(start -0.7874 0.4064)
			(end -0.7874 -0.4064)
			(stroke
				(width 0.1524)
				(type default)
			)
			(layer "F.SilkS")
		)
		(fp_line
			(start -0.12065 -0.305054)
			(end -0.12065 -0.2794)
			(stroke
				(width 0.1)
				(type default)
			)
			(layer "F.Fab")
		)
		(fp_line
			(start -0.67945 -0.305054)
			(end -0.12065 -0.305054)
			(stroke
				(width 0.1)
				(type default)
			)
			(layer "F.Fab")
		)
		(fp_line
			(start 0.67945 -0.3048)
			(end 0.67945 0.3048)
			(stroke
				(width 0.1)
				(type default)
			)
			(layer "F.Fab")
		)
		(fp_line
			(start 0.12065 -0.3048)
			(end 0.67945 -0.3048)
			(stroke
				(width 0.1)
				(type default)
			)
			(layer "F.Fab")
		)
		(fp_line
			(start 0.12065 -0.2794)
			(end 0.12065 -0.3048)
			(stroke
				(width 0.1)
				(type default)
			)
			(layer "F.Fab")
		)
		(fp_line
			(start -0.12065 -0.2794)
			(end 0.12065 -0.2794)
			(stroke
				(width 0.1)
				(type default)
			)
			(layer "F.Fab")
		)
		(fp_line
			(start 0.120396 0.2794)
			(end -0.12065 0.2794)
			(stroke
				(width 0.1)
				(type default)
			)
			(layer "F.Fab")
		)
		(fp_line
			(start -0.12065 0.2794)
			(end -0.12065 0.3048)
			(stroke
				(width 0.1)
				(type default)
			)
			(layer "F.Fab")
		)
		(fp_line
			(start 0.67945 0.3048)
			(end 0.120396 0.3048)
			(stroke
				(width 0.1)
				(type default)
			)
			(layer "F.Fab")
		)
		(fp_line
			(start 0.120396 0.3048)
			(end 0.120396 0.2794)
			(stroke
				(width 0.1)
				(type default)
			)
			(layer "F.Fab")
		)
		(fp_line
			(start -0.12065 0.3048)
			(end -0.67945 0.3048)
			(stroke
				(width 0.1)
				(type default)
			)
			(layer "F.Fab")
		)
		(fp_line
			(start -0.67945 0.3048)
			(end -0.67945 -0.305054)
			(stroke
				(width 0.1)
				(type default)
			)
			(layer "F.Fab")
		)
		(pad "1" smd circle
			(at -0.40005 0 90)
			(size 0 0)
			(layers "F.Cu" "F.Mask" "F.Paste")
			(net "FM_CPU1_SLP_S5_N")
		)
		(pad "2" smd circle
			(at 0.40005 0 90)
			(size 0 0)
			(layers "F.Cu" "F.Mask" "F.Paste")
			(net "CPU1_SLP_S5_N")
		)
	)
	(footprint ""
		(layer "F.Cu")
		(at 301.161704 -430.28362 90)
		(property "Reference" "R6822"
			(at 0 0 90)
			(layer "F.SilkS")
			(hide yes)
			(effects
				(font
					(size 1.27 1.27)
				)
			)
		)
		(property "Value" ""
			(at 0 0 90)
			(layer "F.Fab")
			(effects
				(font
					(size 1.27 1.27)
				)
			)
		)
		(duplicate_pad_numbers_are_jumpers no)
		(fp_line
			(start 0.32512 -0.175006)
			(end 0.32512 0.175006)
			(stroke
				(width 0.1)
				(type default)
			)
			(layer "F.Fab")
		)
		(fp_line
			(start -0.32512 -0.175006)
			(end 0.32512 -0.175006)
			(stroke
				(width 0.1)
				(type default)
			)
			(layer "F.Fab")
		)
		(fp_line
			(start 0.32512 0.175006)
			(end -0.32512 0.175006)
			(stroke
				(width 0.1)
				(type default)
			)
			(layer "F.Fab")
		)
		(fp_line
			(start -0.32512 0.175006)
			(end -0.32512 -0.175006)
			(stroke
				(width 0.1)
				(type default)
			)
			(layer "F.Fab")
		)
		(pad "1" smd rect
			(at -0.2667 0 90)
			(size 0.3048 0.381)
			(layers "F.Cu" "F.Mask" "F.Paste")
			(net "U11_E2")
		)
		(pad "2" smd rect
			(at 0.2667 0 270)
			(size 0.3048 0.381)
			(layers "F.Cu" "F.Mask" "F.Paste")
			(net "GND")
		)
	)
	(footprint ""
		(layer "F.Cu")
		(at 118.846346 -408.517344 -90)
		(property "Reference" "C6695"
			(at 0 0 270)
			(layer "F.SilkS")
			(hide yes)
			(effects
				(font
					(size 1.27 1.27)
				)
			)
		)
		(property "Value" ""
			(at 0 0 270)
			(layer "F.Fab")
			(effects
				(font
					(size 1.27 1.27)
				)
			)
		)
		(duplicate_pad_numbers_are_jumpers no)
		(fp_line
			(start -0.299974 0.150114)
			(end -0.299974 -0.150114)
			(stroke
				(width 0.1)
				(type default)
			)
			(layer "F.Fab")
		)
		(fp_line
			(start 0.299974 0.150114)
			(end -0.299974 0.150114)
			(stroke
				(width 0.1)
				(type default)
			)
			(layer "F.Fab")
		)
		(fp_line
			(start -0.299974 -0.150114)
			(end 0.299974 -0.150114)
			(stroke
				(width 0.1)
				(type default)
			)
			(layer "F.Fab")
		)
		(fp_line
			(start 0.299974 -0.150114)
			(end 0.299974 0.150114)
			(stroke
				(width 0.1)
				(type default)
			)
			(layer "F.Fab")
		)
		(pad "1" smd rect
			(at -0.2667 0 270)
			(size 0.3048 0.381)
			(layers "F.Cu" "F.Mask" "F.Paste")
			(net "P5E_CPU1_P2_TX_BUF_C_DP<1>")
		)
		(pad "2" smd rect
			(at 0.2667 0 270)
			(size 0.3048 0.381)
			(layers "F.Cu" "F.Mask" "F.Paste")
			(net "P5E_CPU1_P2_TX_BUF_DP<1>")
		)
	)
	(footprint ""
		(layer "F.Cu")
		(at 114.490246 -399.327116 -90)
		(property "Reference" "C1067"
			(at 0 0 270)
			(layer "F.SilkS")
			(hide yes)
			(effects
				(font
					(size 1.27 1.27)
				)
			)
		)
		(property "Value" ""
			(at 0 0 270)
			(layer "F.Fab")
			(effects
				(font
					(size 1.27 1.27)
				)
			)
		)
		(duplicate_pad_numbers_are_jumpers no)
		(fp_line
			(start -0.299974 0.150114)
			(end -0.299974 -0.150114)
			(stroke
				(width 0.1)
				(type default)
			)
			(layer "F.Fab")
		)
		(fp_line
			(start 0.299974 0.150114)
			(end -0.299974 0.150114)
			(stroke
				(width 0.1)
				(type default)
			)
			(layer "F.Fab")
		)
		(fp_line
			(start -0.299974 -0.150114)
			(end 0.299974 -0.150114)
			(stroke
				(width 0.1)
				(type default)
			)
			(layer "F.Fab")
		)
		(fp_line
			(start 0.299974 -0.150114)
			(end 0.299974 0.150114)
			(stroke
				(width 0.1)
				(type default)
			)
			(layer "F.Fab")
		)
		(pad "1" smd rect
			(at -0.2667 0 270)
			(size 0.3048 0.381)
			(layers "F.Cu" "F.Mask" "F.Paste")
			(net "P3V3_AUX")
		)
		(pad "2" smd rect
			(at 0.2667 0 270)
			(size 0.3048 0.381)
			(layers "F.Cu" "F.Mask" "F.Paste")
			(net "GND")
		)
	)
	(footprint ""
		(layer "F.Cu")
		(at 166.18077 -394.3604 -90)
		(property "Reference" "R6795"
			(at 0 0 270)
			(layer "F.SilkS")
			(hide yes)
			(effects
				(font
					(size 1.27 1.27)
				)
			)
		)
		(property "Value" ""
			(at 0 0 270)
			(layer "F.Fab")
			(effects
				(font
					(size 1.27 1.27)
				)
			)
		)
		(duplicate_pad_numbers_are_jumpers no)
		(fp_line
			(start -0.32512 0.175006)
			(end -0.32512 -0.175006)
			(stroke
				(width 0.1)
				(type default)
			)
			(layer "F.Fab")
		)
		(fp_line
			(start 0.32512 0.175006)
			(end -0.32512 0.175006)
			(stroke
				(width 0.1)
				(type default)
			)
			(layer "F.Fab")
		)
		(fp_line
			(start -0.32512 -0.175006)
			(end 0.32512 -0.175006)
			(stroke
				(width 0.1)
				(type default)
			)
			(layer "F.Fab")
		)
		(fp_line
			(start 0.32512 -0.175006)
			(end 0.32512 0.175006)
			(stroke
				(width 0.1)
				(type default)
			)
			(layer "F.Fab")
		)
		(pad "1" smd rect
			(at -0.2667 0 270)
			(size 0.3048 0.381)
			(layers "F.Cu" "F.Mask" "F.Paste")
			(net "RT_CPU1_P2_VQPS")
		)
		(pad "2" smd rect
			(at 0.2667 0 90)
			(size 0.3048 0.381)
			(layers "F.Cu" "F.Mask" "F.Paste")
			(net "GND")
		)
	)
)
